FILE_TYPE=LIBRARY_PARTS;
TIME=' Created/Modified on Fri Jan 14 14:50:35 2011' ;
primitive 'BSS138DW7F';
  pin
    'G1':
      PIN_NUMBER='(2)';
      INPUT_LOAD='(-0.01,0.01)';
      OUTPUT_LOAD='(1.0,-1.0)';
      BIDIRECTIONAL='TRUE';
    'G2':
      PIN_NUMBER='(5)';
      INPUT_LOAD='(-0.01,0.01)';
      OUTPUT_LOAD='(1.0,-1.0)';
      BIDIRECTIONAL='TRUE';
    'S1':
      PIN_NUMBER='(1)';
      INPUT_LOAD='(-0.01,0.01)';
      OUTPUT_LOAD='(1.0,-1.0)';
      BIDIRECTIONAL='TRUE';
    'S2':
      PIN_NUMBER='(4)';
      INPUT_LOAD='(-0.01,0.01)';
      OUTPUT_LOAD='(1.0,-1.0)';
      BIDIRECTIONAL='TRUE';
    'D1':
      PIN_NUMBER='(6)';
      INPUT_LOAD='(-0.01,0.01)';
      OUTPUT_LOAD='(1.0,-1.0)';
      BIDIRECTIONAL='TRUE';
    'D2':
      PIN_NUMBER='(3)';
      INPUT_LOAD='(-0.01,0.01)';
      OUTPUT_LOAD='(1.0,-1.0)';
      BIDIRECTIONAL='TRUE';
  end_pin;
  body
    CLASS='DISCRETE';
    PART_NAME='BSS138DW7F';
    PHYS_DES_PREFIX='Q';
  end_body;
end_primitive;
END.
